(kicad_pcb
	(version 20260206)
	(generator "pcbnew")
	(generator_version "10.0")
	(general
		(thickness 1.6)
		(legacy_teardrops no)
	)
	(paper "A4")
	(title_block
		(title "v1-chassis-manager — T6M_CM_d_v01_1031_1645.brd")
		(comment 1 "Open CloudServer (Microsoft) / footprints 2414-2424 of 2512")
	)
	(layers
		(0 "F.Cu" signal "TOP")
		(4 "In1.Cu" signal "GND1")
		(6 "In2.Cu" signal "IN1")
		(8 "In3.Cu" signal "VCC1")
		(10 "In4.Cu" signal "VCC2")
		(12 "In5.Cu" signal "GND2")
		(14 "In6.Cu" signal "IN2")
		(16 "In7.Cu" signal "IN3")
		(18 "In8.Cu" signal "GND3")
		(2 "B.Cu" signal "BOTTOM")
		(9 "F.Adhes" user "F.Adhesive")
		(11 "B.Adhes" user "B.Adhesive")
		(13 "F.Paste" user "Package Geometry/Pastemask Top")
		(15 "B.Paste" user "Package Geometry/Pastemask Bottom")
		(5 "F.SilkS" user "Ref Des/Silkscreen Top")
		(7 "B.SilkS" user "Ref Des/Silkscreen Bottom")
		(1 "F.Mask" user "Board Geometry/Soldermask Top")
		(3 "B.Mask" user "Board Geometry/Soldermask Bottom")
		(17 "Dwgs.User" user "User.Drawings")
		(19 "Cmts.User" user "User.Comments")
		(21 "Eco1.User" user "User.Eco1")
		(23 "Eco2.User" user "User.Eco2")
		(25 "Edge.Cuts" user "Board Geometry/Outline")
		(27 "Margin" user)
		(31 "F.CrtYd" user "Package Geometry/Place Bound Top")
		(29 "B.CrtYd" user "Package Geometry/Place Bound Bottom")
		(35 "F.Fab" user "Ref Des/Assembly Top")
		(33 "B.Fab" user "Ref Des/Assembly Bottom")
	)
	(footprint ""
		(layer "B.Cu")
		(at 113.01476 -188.126624 -90)
		(property "Reference" "C727"
			(at -4.080256 -0.709168 270)
			(unlocked yes)
			(layer "B.SilkS")
			(effects
				(font
					(size 0.7874 0.5842)
					(thickness 0.1524)
				)
				(justify left mirror)
			)
		)
		(property "Value" ""
			(at 0 0 90)
			(layer "B.Fab")
			(effects
				(font
					(size 1.27 1.27)
				)
				(justify mirror)
			)
		)
		(duplicate_pad_numbers_are_jumpers no)
		(fp_line
			(start -0.7874 0.4064)
			(end 0.7874 0.4064)
			(stroke
				(width 0.1524)
				(type default)
			)
			(layer "B.SilkS")
		)
		(fp_line
			(start 0.7874 0.4064)
			(end 0.7874 -0.4064)
			(stroke
				(width 0.1524)
				(type default)
			)
			(layer "B.SilkS")
		)
		(fp_line
			(start 0 0.381)
			(end 0 -0.381)
			(stroke
				(width 0.1524)
				(type default)
			)
			(layer "B.SilkS")
		)
		(fp_line
			(start -0.7874 -0.4064)
			(end -0.7874 0.4064)
			(stroke
				(width 0.1524)
				(type default)
			)
			(layer "B.SilkS")
		)
		(fp_line
			(start 0.7874 -0.4064)
			(end -0.7874 -0.4064)
			(stroke
				(width 0.1524)
				(type default)
			)
			(layer "B.SilkS")
		)
		(fp_poly
			(pts
				(xy 0.5334 0.254) (xy 0.635 0.254) (xy 0.635 0.2286) (xy 0.635 -0.254) (xy 0.5334 -0.254) (xy 0.5334 -0.2794)
				(xy -0.5334 -0.2794) (xy -0.5334 -0.254) (xy -0.635 -0.254) (xy -0.635 0.254) (xy -0.5334 0.254)
				(xy -0.5334 0.2794) (xy 0.508 0.2794) (xy 0.5334 0.2794)
			)
			(stroke
				(width 0)
				(type default)
			)
			(fill no)
			(layer "B.CrtYd")
		)
		(pad "1" smd rect
			(at -0.40005 0 90)
			(size 0.4572 0.508)
			(layers "B.Cu" "B.Mask" "B.Paste")
			(net "UART_T7_NODE2_TXD_R")
		)
		(pad "2" smd rect
			(at 0.40005 0 90)
			(size 0.4572 0.508)
			(layers "B.Cu" "B.Mask" "B.Paste")
			(net "GND")
		)
	)
	(footprint ""
		(layer "B.Cu")
		(at 74.02576 -188.126624 -90)
		(property "Reference" "C674"
			(at -4.318254 0.406146 270)
			(unlocked yes)
			(layer "B.SilkS")
			(effects
				(font
					(size 0.7874 0.5842)
					(thickness 0.1524)
				)
				(justify left mirror)
			)
		)
		(property "Value" ""
			(at 0 0 90)
			(layer "B.Fab")
			(effects
				(font
					(size 1.27 1.27)
				)
				(justify mirror)
			)
		)
		(duplicate_pad_numbers_are_jumpers no)
		(fp_line
			(start -0.7874 0.4064)
			(end 0.7874 0.4064)
			(stroke
				(width 0.1524)
				(type default)
			)
			(layer "B.SilkS")
		)
		(fp_line
			(start 0.7874 0.4064)
			(end 0.7874 -0.4064)
			(stroke
				(width 0.1524)
				(type default)
			)
			(layer "B.SilkS")
		)
		(fp_line
			(start 0 0.381)
			(end 0 -0.381)
			(stroke
				(width 0.1524)
				(type default)
			)
			(layer "B.SilkS")
		)
		(fp_line
			(start -0.7874 -0.4064)
			(end -0.7874 0.4064)
			(stroke
				(width 0.1524)
				(type default)
			)
			(layer "B.SilkS")
		)
		(fp_line
			(start 0.7874 -0.4064)
			(end -0.7874 -0.4064)
			(stroke
				(width 0.1524)
				(type default)
			)
			(layer "B.SilkS")
		)
		(fp_poly
			(pts
				(xy 0.5334 0.254) (xy 0.635 0.254) (xy 0.635 0.2286) (xy 0.635 -0.254) (xy 0.5334 -0.254) (xy 0.5334 -0.2794)
				(xy -0.5334 -0.2794) (xy -0.5334 -0.254) (xy -0.635 -0.254) (xy -0.635 0.254) (xy -0.5334 0.254)
				(xy -0.5334 0.2794) (xy 0.508 0.2794) (xy 0.5334 0.2794)
			)
			(stroke
				(width 0)
				(type default)
			)
			(fill no)
			(layer "B.CrtYd")
		)
		(pad "1" smd rect
			(at -0.40005 0 90)
			(size 0.4572 0.508)
			(layers "B.Cu" "B.Mask" "B.Paste")
			(net "UART_T3_NODE1_TXD_R")
		)
		(pad "2" smd rect
			(at 0.40005 0 90)
			(size 0.4572 0.508)
			(layers "B.Cu" "B.Mask" "B.Paste")
			(net "GND")
		)
	)
	(footprint ""
		(layer "B.Cu")
		(at 69.330062 -29.394658 -90)
		(property "Reference" "C194"
			(at -1.449832 0.256794 270)
			(unlocked yes)
			(layer "B.SilkS")
			(effects
				(font
					(size 0.7874 0.5842)
					(thickness 0.1524)
				)
				(justify left mirror)
			)
		)
		(property "Value" ""
			(at 0 0 90)
			(layer "B.Fab")
			(effects
				(font
					(size 1.27 1.27)
				)
				(justify mirror)
			)
		)
		(duplicate_pad_numbers_are_jumpers no)
		(fp_line
			(start -0.7874 0.406146)
			(end 0.7874 0.406146)
			(stroke
				(width 0.1524)
				(type default)
			)
			(layer "B.SilkS")
		)
		(fp_line
			(start 0.7874 0.406146)
			(end 0.7874 -0.406146)
			(stroke
				(width 0.1524)
				(type default)
			)
			(layer "B.SilkS")
		)
		(fp_line
			(start 0 0.381)
			(end 0 -0.381)
			(stroke
				(width 0.1524)
				(type default)
			)
			(layer "B.SilkS")
		)
		(fp_line
			(start -0.7874 -0.406146)
			(end -0.7874 0.406146)
			(stroke
				(width 0.1524)
				(type default)
			)
			(layer "B.SilkS")
		)
		(fp_line
			(start 0.7874 -0.406146)
			(end -0.7874 -0.406146)
			(stroke
				(width 0.1524)
				(type default)
			)
			(layer "B.SilkS")
		)
		(fp_poly
			(pts
				(xy 0.5334 0.254) (xy 0.635 0.254) (xy 0.635 0.2286) (xy 0.635 -0.254) (xy 0.5334 -0.254) (xy 0.5334 -0.2794)
				(xy -0.5334 -0.2794) (xy -0.5334 -0.254) (xy -0.635 -0.254) (xy -0.635 0.254) (xy -0.5334 0.254)
				(xy -0.5334 0.2794) (xy 0.508 0.2794) (xy 0.5334 0.2794)
			)
			(stroke
				(width 0)
				(type default)
			)
			(fill no)
			(layer "B.CrtYd")
		)
		(pad "1" smd rect
			(at -0.40005 0 90)
			(size 0.4572 0.508)
			(layers "B.Cu" "B.Mask" "B.Paste")
			(net "P1V5_NODE1_DDR3_VREF_A_A")
		)
		(pad "2" smd rect
			(at 0.40005 0 90)
			(size 0.4572 0.508)
			(layers "B.Cu" "B.Mask" "B.Paste")
			(net "GND")
		)
	)
	(footprint ""
		(layer "B.Cu")
		(at 57.65673 -68.727828 -90)
		(property "Reference" "C94"
			(at 34.283142 14.25194 270)
			(unlocked yes)
			(layer "B.SilkS")
			(effects
				(font
					(size 0.7874 0.5842)
					(thickness 0.1524)
				)
				(justify left mirror)
			)
		)
		(property "Value" ""
			(at 0 0 90)
			(layer "B.Fab")
			(effects
				(font
					(size 1.27 1.27)
				)
				(justify mirror)
			)
		)
		(duplicate_pad_numbers_are_jumpers no)
		(fp_line
			(start -0.7874 0.4064)
			(end 0.7874 0.4064)
			(stroke
				(width 0.1524)
				(type default)
			)
			(layer "B.SilkS")
		)
		(fp_line
			(start 0.7874 0.4064)
			(end 0.7874 -0.4064)
			(stroke
				(width 0.1524)
				(type default)
			)
			(layer "B.SilkS")
		)
		(fp_line
			(start 0 0.381)
			(end 0 -0.381)
			(stroke
				(width 0.1524)
				(type default)
			)
			(layer "B.SilkS")
		)
		(fp_line
			(start -0.7874 -0.4064)
			(end -0.7874 0.4064)
			(stroke
				(width 0.1524)
				(type default)
			)
			(layer "B.SilkS")
		)
		(fp_line
			(start 0.7874 -0.4064)
			(end -0.7874 -0.4064)
			(stroke
				(width 0.1524)
				(type default)
			)
			(layer "B.SilkS")
		)
		(fp_poly
			(pts
				(xy 0.5334 0.254) (xy 0.635 0.254) (xy 0.635 0.2286) (xy 0.635 -0.254) (xy 0.5334 -0.254) (xy 0.5334 -0.2794)
				(xy -0.5334 -0.2794) (xy -0.5334 -0.254) (xy -0.635 -0.254) (xy -0.635 0.254) (xy -0.5334 0.254)
				(xy -0.5334 0.2794) (xy 0.508 0.2794) (xy 0.5334 0.2794)
			)
			(stroke
				(width 0)
				(type default)
			)
			(fill no)
			(layer "B.CrtYd")
		)
		(pad "1" smd rect
			(at -0.40005 0 90)
			(size 0.4572 0.508)
			(layers "B.Cu" "B.Mask" "B.Paste")
			(net "P1V5_SFRPLL_NODE1")
		)
		(pad "2" smd rect
			(at 0.40005 0 90)
			(size 0.4572 0.508)
			(layers "B.Cu" "B.Mask" "B.Paste")
			(net "GND")
		)
	)
	(footprint ""
		(layer "B.Cu")
		(at 165.21938 -154.315922 180)
		(property "Reference" "C467"
			(at 1.083564 -0.624332 0)
			(unlocked yes)
			(layer "B.SilkS")
			(effects
				(font
					(size 0.7874 0.5842)
					(thickness 0.1524)
				)
				(justify left mirror)
			)
		)
		(property "Value" ""
			(at 0 0 0)
			(layer "B.Fab")
			(effects
				(font
					(size 1.27 1.27)
				)
				(justify mirror)
			)
		)
		(duplicate_pad_numbers_are_jumpers no)
		(fp_line
			(start 0.7874 0.4064)
			(end 0.7874 -0.4064)
			(stroke
				(width 0.1524)
				(type default)
			)
			(layer "B.SilkS")
		)
		(fp_line
			(start 0.7874 -0.4064)
			(end -0.7874 -0.4064)
			(stroke
				(width 0.1524)
				(type default)
			)
			(layer "B.SilkS")
		)
		(fp_line
			(start 0 0.381)
			(end 0 -0.381)
			(stroke
				(width 0.1524)
				(type default)
			)
			(layer "B.SilkS")
		)
		(fp_line
			(start -0.7874 0.4064)
			(end 0.7874 0.4064)
			(stroke
				(width 0.1524)
				(type default)
			)
			(layer "B.SilkS")
		)
		(fp_line
			(start -0.7874 -0.4064)
			(end -0.7874 0.4064)
			(stroke
				(width 0.1524)
				(type default)
			)
			(layer "B.SilkS")
		)
		(fp_poly
			(pts
				(xy 0.5334 0.254) (xy 0.635 0.254) (xy 0.635 0.2286) (xy 0.635 -0.254) (xy 0.5334 -0.254) (xy 0.5334 -0.2794)
				(xy -0.5334 -0.2794) (xy -0.5334 -0.254) (xy -0.635 -0.254) (xy -0.635 0.254) (xy -0.5334 0.254)
				(xy -0.5334 0.2794) (xy 0.508 0.2794) (xy 0.5334 0.2794)
			)
			(stroke
				(width 0)
				(type default)
			)
			(fill no)
			(layer "B.CrtYd")
		)
		(pad "1" smd rect
			(at -0.40005 0)
			(size 0.4572 0.508)
			(layers "B.Cu" "B.Mask" "B.Paste")
			(net "P1V05_LAN2")
		)
		(pad "2" smd rect
			(at 0.40005 0)
			(size 0.4572 0.508)
			(layers "B.Cu" "B.Mask" "B.Paste")
			(net "GND")
		)
	)
	(footprint ""
		(layer "B.Cu")
		(at 63.16726 -99.189032 -90)
		(property "Reference" "R70"
			(at -0.99441 -0.003302 270)
			(unlocked yes)
			(layer "B.SilkS")
			(effects
				(font
					(size 0.7874 0.5842)
					(thickness 0.1524)
				)
				(justify left mirror)
			)
		)
		(property "Value" ""
			(at 0 0 90)
			(layer "B.Fab")
			(effects
				(font
					(size 1.27 1.27)
				)
				(justify mirror)
			)
		)
		(duplicate_pad_numbers_are_jumpers no)
		(fp_line
			(start -0.7874 0.4064)
			(end 0.7874 0.4064)
			(stroke
				(width 0.1524)
				(type default)
			)
			(layer "B.SilkS")
		)
		(fp_line
			(start 0.7874 0.4064)
			(end 0.7874 -0.4064)
			(stroke
				(width 0.1524)
				(type default)
			)
			(layer "B.SilkS")
		)
		(fp_line
			(start -0.7874 -0.4064)
			(end -0.7874 0.4064)
			(stroke
				(width 0.1524)
				(type default)
			)
			(layer "B.SilkS")
		)
		(fp_line
			(start 0.7874 -0.4064)
			(end -0.7874 -0.4064)
			(stroke
				(width 0.1524)
				(type default)
			)
			(layer "B.SilkS")
		)
		(fp_poly
			(pts
				(xy 0.508 0.2794) (xy 0.508 0.2286) (xy 0.635 0.2286) (xy 0.635 -0.254) (xy 0.5334 -0.254) (xy 0.5334 -0.2794)
				(xy -0.5334 -0.2794) (xy -0.5334 -0.254) (xy -0.635 -0.254) (xy -0.635 0.254) (xy -0.5334 0.254)
				(xy -0.5334 0.2794)
			)
			(stroke
				(width 0)
				(type default)
			)
			(fill no)
			(layer "B.CrtYd")
		)
		(pad "1" smd rect
			(at -0.40005 0 90)
			(size 0.4572 0.508)
			(layers "B.Cu" "B.Mask" "B.Paste")
			(net "P3V3_NODE1")
		)
		(pad "2" smd rect
			(at 0.40005 0 90)
			(size 0.4572 0.508)
			(layers "B.Cu" "B.Mask" "B.Paste")
			(net "IRQ_CPU_NODE1_SERIAL")
		)
	)
	(footprint ""
		(layer "B.Cu")
		(at 66.194686 -118.758462 -90)
		(property "Reference" "R333"
			(at 5.056632 0.375158 270)
			(unlocked yes)
			(layer "B.SilkS")
			(effects
				(font
					(size 0.7874 0.5842)
					(thickness 0.1524)
				)
				(justify left mirror)
			)
		)
		(property "Value" ""
			(at 0 0 90)
			(layer "B.Fab")
			(effects
				(font
					(size 1.27 1.27)
				)
				(justify mirror)
			)
		)
		(duplicate_pad_numbers_are_jumpers no)
		(fp_line
			(start -0.7874 0.4064)
			(end 0.7874 0.4064)
			(stroke
				(width 0.1524)
				(type default)
			)
			(layer "B.SilkS")
		)
		(fp_line
			(start 0.7874 0.4064)
			(end 0.7874 -0.4064)
			(stroke
				(width 0.1524)
				(type default)
			)
			(layer "B.SilkS")
		)
		(fp_line
			(start -0.7874 -0.4064)
			(end -0.7874 0.4064)
			(stroke
				(width 0.1524)
				(type default)
			)
			(layer "B.SilkS")
		)
		(fp_line
			(start 0.7874 -0.4064)
			(end -0.7874 -0.4064)
			(stroke
				(width 0.1524)
				(type default)
			)
			(layer "B.SilkS")
		)
		(fp_poly
			(pts
				(xy 0.508 0.2794) (xy 0.508 0.2286) (xy 0.635 0.2286) (xy 0.635 -0.254) (xy 0.5334 -0.254) (xy 0.5334 -0.2794)
				(xy -0.5334 -0.2794) (xy -0.5334 -0.254) (xy -0.635 -0.254) (xy -0.635 0.254) (xy -0.5334 0.254)
				(xy -0.5334 0.2794)
			)
			(stroke
				(width 0)
				(type default)
			)
			(fill no)
			(layer "B.CrtYd")
		)
		(pad "1" smd rect
			(at -0.40005 0 90)
			(size 0.4572 0.508)
			(layers "B.Cu" "B.Mask" "B.Paste")
			(net "P3V3_NODE1")
		)
		(pad "2" smd rect
			(at 0.40005 0 90)
			(size 0.4572 0.508)
			(layers "B.Cu" "B.Mask" "B.Paste")
			(net "BMC_ROMA17")
		)
	)
	(footprint ""
		(layer "B.Cu")
		(at 167.902636 -173.284642 90)
		(property "Reference" "C918"
			(at 0.928116 -0.235966 270)
			(unlocked yes)
			(layer "B.SilkS")
			(effects
				(font
					(size 0.7874 0.5842)
					(thickness 0.1524)
				)
				(justify left mirror)
			)
		)
		(property "Value" ""
			(at 0 0 90)
			(layer "B.Fab")
			(effects
				(font
					(size 1.27 1.27)
				)
				(justify mirror)
			)
		)
		(duplicate_pad_numbers_are_jumpers no)
		(fp_line
			(start 0.7874 -0.4064)
			(end -0.7874 -0.4064)
			(stroke
				(width 0.1524)
				(type default)
			)
			(layer "B.SilkS")
		)
		(fp_line
			(start -0.7874 -0.4064)
			(end -0.7874 0.4064)
			(stroke
				(width 0.1524)
				(type default)
			)
			(layer "B.SilkS")
		)
		(fp_line
			(start 0 0.381)
			(end 0 -0.381)
			(stroke
				(width 0.1524)
				(type default)
			)
			(layer "B.SilkS")
		)
		(fp_line
			(start 0.7874 0.4064)
			(end 0.7874 -0.4064)
			(stroke
				(width 0.1524)
				(type default)
			)
			(layer "B.SilkS")
		)
		(fp_line
			(start -0.7874 0.4064)
			(end 0.7874 0.4064)
			(stroke
				(width 0.1524)
				(type default)
			)
			(layer "B.SilkS")
		)
		(fp_poly
			(pts
				(xy 0.5334 0.254) (xy 0.635 0.254) (xy 0.635 0.2286) (xy 0.635 -0.254) (xy 0.5334 -0.254) (xy 0.5334 -0.2794)
				(xy -0.5334 -0.2794) (xy -0.5334 -0.254) (xy -0.635 -0.254) (xy -0.635 0.254) (xy -0.5334 0.254)
				(xy -0.5334 0.2794) (xy 0.508 0.2794) (xy 0.5334 0.2794)
			)
			(stroke
				(width 0)
				(type default)
			)
			(fill no)
			(layer "B.CrtYd")
		)
		(pad "1" smd rect
			(at -0.40005 0 270)
			(size 0.4572 0.508)
			(layers "B.Cu" "B.Mask" "B.Paste")
			(net "P3V3_NODE1")
		)
		(pad "2" smd rect
			(at 0.40005 0 270)
			(size 0.4572 0.508)
			(layers "B.Cu" "B.Mask" "B.Paste")
			(net "GND")
		)
	)
	(footprint ""
		(layer "B.Cu")
		(at 76.570078 -129.388616 -90)
		(property "Reference" "R258"
			(at -1.582166 0.064516 270)
			(unlocked yes)
			(layer "B.SilkS")
			(effects
				(font
					(size 0.7874 0.5842)
					(thickness 0.1524)
				)
				(justify left mirror)
			)
		)
		(property "Value" ""
			(at 0 0 90)
			(layer "B.Fab")
			(effects
				(font
					(size 1.27 1.27)
				)
				(justify mirror)
			)
		)
		(duplicate_pad_numbers_are_jumpers no)
		(fp_line
			(start -0.7874 0.4064)
			(end 0.7874 0.4064)
			(stroke
				(width 0.1524)
				(type default)
			)
			(layer "B.SilkS")
		)
		(fp_line
			(start 0.7874 0.4064)
			(end 0.7874 -0.4064)
			(stroke
				(width 0.1524)
				(type default)
			)
			(layer "B.SilkS")
		)
		(fp_line
			(start -0.7874 -0.4064)
			(end -0.7874 0.4064)
			(stroke
				(width 0.1524)
				(type default)
			)
			(layer "B.SilkS")
		)
		(fp_line
			(start 0.7874 -0.4064)
			(end -0.7874 -0.4064)
			(stroke
				(width 0.1524)
				(type default)
			)
			(layer "B.SilkS")
		)
		(fp_poly
			(pts
				(xy 0.508 0.2794) (xy 0.508 0.2286) (xy 0.635 0.2286) (xy 0.635 -0.254) (xy 0.5334 -0.254) (xy 0.5334 -0.2794)
				(xy -0.5334 -0.2794) (xy -0.5334 -0.254) (xy -0.635 -0.254) (xy -0.635 0.254) (xy -0.5334 0.254)
				(xy -0.5334 0.2794)
			)
			(stroke
				(width 0)
				(type default)
			)
			(fill no)
			(layer "B.CrtYd")
		)
		(pad "1" smd rect
			(at -0.40005 0 90)
			(size 0.4572 0.508)
			(layers "B.Cu" "B.Mask" "B.Paste")
			(net "GND")
		)
		(pad "2" smd rect
			(at 0.40005 0 90)
			(size 0.4572 0.508)
			(layers "B.Cu" "B.Mask" "B.Paste")
			(net "LPC_CLK_AST")
		)
	)
	(footprint ""
		(layer "B.Cu")
		(at 74.223372 -80.514698 90)
		(property "Reference" "C87"
			(at -32.158686 -14.55039 270)
			(unlocked yes)
			(layer "B.SilkS")
			(effects
				(font
					(size 0.7874 0.5842)
					(thickness 0.1524)
				)
				(justify left mirror)
			)
		)
		(property "Value" ""
			(at 0 0 90)
			(layer "B.Fab")
			(effects
				(font
					(size 1.27 1.27)
				)
				(justify mirror)
			)
		)
		(duplicate_pad_numbers_are_jumpers no)
		(fp_line
			(start 0.7874 -0.4064)
			(end -0.7874 -0.4064)
			(stroke
				(width 0.1524)
				(type default)
			)
			(layer "B.SilkS")
		)
		(fp_line
			(start -0.7874 -0.4064)
			(end -0.7874 0.4064)
			(stroke
				(width 0.1524)
				(type default)
			)
			(layer "B.SilkS")
		)
		(fp_line
			(start 0 0.381)
			(end 0 -0.381)
			(stroke
				(width 0.1524)
				(type default)
			)
			(layer "B.SilkS")
		)
		(fp_line
			(start 0.7874 0.4064)
			(end 0.7874 -0.4064)
			(stroke
				(width 0.1524)
				(type default)
			)
			(layer "B.SilkS")
		)
		(fp_line
			(start -0.7874 0.4064)
			(end 0.7874 0.4064)
			(stroke
				(width 0.1524)
				(type default)
			)
			(layer "B.SilkS")
		)
		(fp_poly
			(pts
				(xy 0.5334 0.254) (xy 0.635 0.254) (xy 0.635 0.2286) (xy 0.635 -0.254) (xy 0.5334 -0.254) (xy 0.5334 -0.2794)
				(xy -0.5334 -0.2794) (xy -0.5334 -0.254) (xy -0.635 -0.254) (xy -0.635 0.254) (xy -0.5334 0.254)
				(xy -0.5334 0.2794) (xy 0.508 0.2794) (xy 0.5334 0.2794)
			)
			(stroke
				(width 0)
				(type default)
			)
			(fill no)
			(layer "B.CrtYd")
		)
		(pad "1" smd rect
			(at -0.40005 0 270)
			(size 0.4572 0.508)
			(layers "B.Cu" "B.Mask" "B.Paste")
			(net "PV_VCCP_NODE1")
		)
		(pad "2" smd rect
			(at 0.40005 0 270)
			(size 0.4572 0.508)
			(layers "B.Cu" "B.Mask" "B.Paste")
			(net "GND")
		)
	)
	(footprint ""
		(layer "B.Cu")
		(at 76.415392 -141.288262)
		(property "Reference" "TP6"
			(at 0 0 0)
			(layer "B.SilkS")
			(hide yes)
			(effects
				(font
					(size 1.27 1.27)
				)
				(justify mirror)
			)
		)
		(property "Value" ""
			(at 0 0 0)
			(layer "B.Fab")
			(effects
				(font
					(size 1.27 1.27)
				)
				(justify mirror)
			)
		)
		(duplicate_pad_numbers_are_jumpers no)
		(fp_poly
			(pts
				(arc
					(start 0 -0.381)
					(mid 0 0.381)
					(end 0 -0.381)
				)
			)
			(stroke
				(width 0)
				(type default)
			)
			(fill no)
			(layer "B.CrtYd")
		)
		(pad "1" smd circle
			(at 0 0 180)
			(size 0.762 0.762)
			(layers "B.Cu" "B.Mask" "B.Paste")
			(net "N3975090766")
		)
	)
)
